(kicad_pcb
	(version 20260206)
	(generator "pcbnew")
	(generator_version "10.0")
	(general
		(thickness 1.5755)
		(legacy_teardrops no)
	)
	(paper "A4")
	(title_block
		(title "gnss-rcb-f9t — GPS_MODULE_ZED-F9T.PcbDoc")
		(comment 1 "Time Appliance Project (Time Card) / footprints 1-7 of 44")
	)
	(layers
		(0 "F.Cu" signal "Top Layer")
		(4 "In1.Cu" signal "Int1 (GND)")
		(6 "In2.Cu" signal "Int2 (GND)")
		(2 "B.Cu" signal "Bottom Layer")
		(9 "F.Adhes" user "F.Adhesive")
		(11 "B.Adhes" user "B.Adhesive")
		(13 "F.Paste" user "Top Paste")
		(15 "B.Paste" user "Bottom Paste")
		(5 "F.SilkS" user "Top Overlay")
		(7 "B.SilkS" user "Bottom Overlay")
		(1 "F.Mask" user "Top Solder")
		(3 "B.Mask" user "Bottom Solder")
		(17 "Dwgs.User" user "User.Drawings")
		(19 "Cmts.User" user "User.Comments")
		(21 "Eco1.User" user "User.Eco1")
		(23 "Eco2.User" user "User.Eco2")
		(25 "Edge.Cuts" user)
		(27 "Margin" user)
		(31 "F.CrtYd" user "Top Courtyard")
		(29 "B.CrtYd" user "Bottom Courtyard")
		(35 "F.Fab" user "Top Component Outline")
		(33 "B.Fab" user "Bottom Component Outline")
	)
	(footprint "Vault:LEDS160X80X110-2N_LXFM0603-GR"
		(layer "F.Cu")
		(at 169.7537 116.6597 90)
		(property "Reference" "DS3"
			(at 2.77425 0.62377 0)
			(unlocked yes)
			(layer "F.SilkS")
			(effects
				(font
					(size 0.8 0.8)
					(thickness 0.15)
				)
			)
		)
		(property "Value" "Lumex_SML-LXFM0603SUGCTR"
			(at -3.318002 17.78687 0)
			(unlocked yes)
			(layer "F.SilkS")
			(hide yes)
			(effects
				(font
					(size 1.524 1.524)
					(thickness 0.254)
				)
			)
		)
		(sheetname "ZED-F9T")
		(sheetfile "ZED-F9T.kicad_sch")
		(duplicate_pad_numbers_are_jumpers no)
		(fp_line
			(start -1.6 -0.3)
			(end -1.6 0.3)
			(stroke
				(width 0.1)
				(type solid)
			)
			(layer "F.SilkS")
		)
		(fp_line
			(start 1.7 -0.7)
			(end 1.7 0.7)
			(stroke
				(width 0.1)
				(type solid)
			)
			(layer "F.CrtYd")
		)
		(fp_line
			(start -1.7 -0.7)
			(end 1.7 -0.7)
			(stroke
				(width 0.1)
				(type solid)
			)
			(layer "F.CrtYd")
		)
		(fp_line
			(start -1.7 -0.7)
			(end -1.7 0.7)
			(stroke
				(width 0.1)
				(type solid)
			)
			(layer "F.CrtYd")
		)
		(fp_line
			(start -1.7 0.7)
			(end 1.7 0.7)
			(stroke
				(width 0.1)
				(type solid)
			)
			(layer "F.CrtYd")
		)
		(fp_line
			(start 0.80017 -0.40012)
			(end 0.80017 0.39984)
			(stroke
				(width 0.05)
				(type solid)
			)
			(layer "F.Fab")
		)
		(fp_line
			(start -0.79991 -0.40012)
			(end 0.80017 -0.40012)
			(stroke
				(width 0.05)
				(type solid)
			)
			(layer "F.Fab")
		)
		(fp_line
			(start -0.79991 -0.40012)
			(end -0.79991 0.39984)
			(stroke
				(width 0.05)
				(type solid)
			)
			(layer "F.Fab")
		)
		(fp_line
			(start -0.1 -0.3)
			(end -0.1 0.3)
			(stroke
				(width 0.05)
				(type solid)
			)
			(layer "F.Fab")
		)
		(fp_line
			(start 0.1 -0.2)
			(end -0.1 0)
			(stroke
				(width 0.05)
				(type solid)
			)
			(layer "F.Fab")
		)
		(fp_line
			(start 0.1 -0.2)
			(end 0.1 0.2)
			(stroke
				(width 0.05)
				(type solid)
			)
			(layer "F.Fab")
		)
		(fp_line
			(start -0.1 0)
			(end 0.1 0.2)
			(stroke
				(width 0.05)
				(type solid)
			)
			(layer "F.Fab")
		)
		(fp_line
			(start -0.79991 0.39984)
			(end 0.80017 0.39984)
			(stroke
				(width 0.05)
				(type solid)
			)
			(layer "F.Fab")
		)
		(fp_text_box "${REFERENCE}"
			(start -2.76576 -0.52568)
			(end 2.76577 0.52568)
			(margins 0 0 0 0)
			(layer "F.Fab")
			(effects
				(font
					(face "Arial")
					(size 0.8001 0.8001)
					(thickness 0.254)
				)
				(justify top)
			)
			(border no)
			(stroke
				(width 0.1)
				(type default)
			)
			(knockout no)
		)
		(pad "A" smd rect
			(at 0.825 0 90)
			(size 0.8 0.8)
			(layers "F.Cu" "F.Mask" "F.Paste")
			(net "VCC_ANT")
			(solder_mask_margin 0.05)
			(solder_paste_margin 0)
		)
		(pad "K" smd rect
			(at -0.825 0 90)
			(size 0.8 0.8)
			(layers "F.Cu" "F.Mask" "F.Paste")
			(net "NetDS3_K")
			(solder_mask_margin 0.05)
			(solder_paste_margin 0)
		)
	)
	(footprint "Vault:FP-RMCF0402-MFG"
		(layer "F.Cu")
		(at 168.8647 103.9597 90)
		(property "Reference" "R3"
			(at 2.35981 0.20607 90)
			(unlocked yes)
			(layer "F.SilkS")
			(effects
				(font
					(size 0.8 0.8)
					(thickness 0.15001)
				)
			)
		)
		(property "Value" "1k"
			(at 0.57117 2.378202 90)
			(unlocked yes)
			(layer "F.SilkS")
			(hide yes)
			(effects
				(font
					(size 1.524 1.524)
					(thickness 0.254)
				)
			)
		)
		(sheetname "ZED-F9T")
		(sheetfile "ZED-F9T.kicad_sch")
		(duplicate_pad_numbers_are_jumpers no)
		(fp_line
			(start -0.55 -0.7)
			(end 0.55 -0.7)
			(stroke
				(width 0.2)
				(type solid)
			)
			(layer "F.SilkS")
		)
		(fp_line
			(start -0.55 0.7)
			(end 0.55 0.7)
			(stroke
				(width 0.2)
				(type solid)
			)
			(layer "F.SilkS")
		)
		(fp_line
			(start 0.85 -0.4)
			(end 0.85 0.4)
			(stroke
				(width 0.2)
				(type solid)
			)
			(layer "F.CrtYd")
		)
		(fp_line
			(start -0.85 -0.4)
			(end 0.85 -0.4)
			(stroke
				(width 0.2)
				(type solid)
			)
			(layer "F.CrtYd")
		)
		(fp_line
			(start -0.85 -0.4)
			(end -0.85 0.4)
			(stroke
				(width 0.2)
				(type solid)
			)
			(layer "F.CrtYd")
		)
		(fp_line
			(start -0.85 0.4)
			(end 0.85 0.4)
			(stroke
				(width 0.2)
				(type solid)
			)
			(layer "F.CrtYd")
		)
		(fp_line
			(start 0 -0.5)
			(end 0 0.5)
			(stroke
				(width 0.1)
				(type solid)
			)
			(layer "F.Fab")
		)
		(fp_line
			(start 0.85 -0.4)
			(end 0.85 0.4)
			(stroke
				(width 0.2)
				(type solid)
			)
			(layer "F.Fab")
		)
		(fp_line
			(start -0.85 -0.4)
			(end 0.85 -0.4)
			(stroke
				(width 0.2)
				(type solid)
			)
			(layer "F.Fab")
		)
		(fp_line
			(start -0.85 -0.4)
			(end -0.85 0.4)
			(stroke
				(width 0.2)
				(type solid)
			)
			(layer "F.Fab")
		)
		(fp_line
			(start -0.5 0)
			(end 0.5 0)
			(stroke
				(width 0.1)
				(type solid)
			)
			(layer "F.Fab")
		)
		(fp_line
			(start -0.85 0.4)
			(end 0.85 0.4)
			(stroke
				(width 0.2)
				(type solid)
			)
			(layer "F.Fab")
		)
		(fp_text user "${REFERENCE}"
			(at -0.00001 0.09556 90)
			(unlocked yes)
			(layer "F.Fab")
			(effects
				(font
					(face "Arial")
					(size 0.63 0.63)
					(thickness 0.1)
				)
				(justify left bottom)
			)
		)
		(pad "1" smd rect
			(at -0.5 0 90)
			(size 0.5 0.6)
			(layers "F.Cu" "F.Mask" "F.Paste")
			(net "TXD_OUT")
			(solder_mask_margin 0)
			(solder_paste_margin 0)
		)
		(pad "2" smd rect
			(at 0.5 0 90)
			(size 0.5 0.6)
			(layers "F.Cu" "F.Mask" "F.Paste")
			(net "VCC")
			(solder_mask_margin 0)
			(solder_paste_margin 0)
		)
	)
	(footprint "Vault:CAPC1005X055N"
		(layer "F.Cu")
		(at 156.4441 107.7951)
		(property "Reference" "C2"
			(at 2.055 0.02827 0)
			(unlocked yes)
			(layer "F.SilkS")
			(effects
				(font
					(size 0.8 0.8)
					(thickness 0.15)
				)
			)
		)
		(property "Value" "Murata_GRM155R61E105KA12D"
			(at 17.659825 2.124202 0)
			(unlocked yes)
			(layer "F.SilkS")
			(hide yes)
			(effects
				(font
					(size 1.524 1.524)
					(thickness 0.254)
				)
			)
		)
		(sheetname "ZED-F9T")
		(sheetfile "ZED-F9T.kicad_sch")
		(duplicate_pad_numbers_are_jumpers no)
		(fp_line
			(start -0.95 -0.5)
			(end 0.95 -0.5)
			(stroke
				(width 0.1)
				(type solid)
			)
			(layer "F.CrtYd")
		)
		(fp_line
			(start -0.95 0.5)
			(end -0.95 -0.5)
			(stroke
				(width 0.1)
				(type solid)
			)
			(layer "F.CrtYd")
		)
		(fp_line
			(start -0.95 0.5)
			(end 0.95 0.5)
			(stroke
				(width 0.1)
				(type solid)
			)
			(layer "F.CrtYd")
		)
		(fp_line
			(start 0.95 0.5)
			(end 0.95 -0.5)
			(stroke
				(width 0.1)
				(type solid)
			)
			(layer "F.CrtYd")
		)
		(fp_line
			(start -0.5 -0.25)
			(end 0.5 -0.25)
			(stroke
				(width 0.05)
				(type solid)
			)
			(layer "F.Fab")
		)
		(fp_line
			(start -0.5 0.25)
			(end -0.5 -0.25)
			(stroke
				(width 0.05)
				(type solid)
			)
			(layer "F.Fab")
		)
		(fp_line
			(start -0.5 0.25)
			(end 0.5 0.25)
			(stroke
				(width 0.05)
				(type solid)
			)
			(layer "F.Fab")
		)
		(fp_line
			(start 0.5 0.25)
			(end 0.5 -0.25)
			(stroke
				(width 0.05)
				(type solid)
			)
			(layer "F.Fab")
		)
		(fp_text_box "${REFERENCE}"
			(start -1.09004 -0.20727)
			(end 1.09004 0.20726)
			(margins 0 0 0 0)
			(layer "F.Fab")
			(effects
				(font
					(face "Arial")
					(size 0.315 0.315)
					(thickness 0.254)
				)
				(justify top)
			)
			(border no)
			(stroke
				(width 0.1)
				(type default)
			)
			(knockout no)
		)
		(pad "1" smd rect
			(at -0.46 0)
			(size 0.6 0.62)
			(layers "F.Cu" "F.Mask" "F.Paste")
			(net "VCC")
			(solder_mask_margin 0.05)
			(solder_paste_margin 0)
		)
		(pad "2" smd rect
			(at 0.46 0)
			(size 0.6 0.62)
			(layers "F.Cu" "F.Mask" "F.Paste")
			(net "GND")
			(solder_mask_margin 0.05)
			(solder_paste_margin 0)
		)
	)
	(footprint "GNSS_Receiver_Library:NRPN042MAMS-RC"
		(locked yes)
		(layer "F.Cu")
		(at 178.2601 112.5961 180)
		(property "Reference" "J1"
			(at 5.24079 8.08325 0)
			(unlocked yes)
			(layer "F.SilkS")
			(effects
				(font
					(size 0.8 0.8)
					(thickness 0.15)
				)
			)
		)
		(property "Value" "NRPN042MAMS-RC"
			(at -0.231135 -4.626602 0)
			(unlocked yes)
			(layer "F.SilkS")
			(hide yes)
			(effects
				(font
					(size 1.524 1.524)
					(thickness 0.254)
				)
			)
		)
		(sheetname "ZED-F9T")
		(sheetfile "ZED-F9T.kicad_sch")
		(duplicate_pad_numbers_are_jumpers no)
		(fp_circle
			(center -2.2 0)
			(end -2.2 0.0762)
			(stroke
				(width 0.508)
				(type solid)
			)
			(fill no)
			(layer "F.SilkS")
		)
		(pad "1" smd rect
			(at 0 0 180)
			(size 2.95 1.02)
			(layers "F.Cu" "F.Mask" "F.Paste")
			(net "VCC_ANT")
		)
		(pad "2" smd rect
			(at 4.55 0 180)
			(size 2.95 1.02)
			(layers "F.Cu" "F.Mask" "F.Paste")
			(net "VCC")
		)
		(pad "3" smd rect
			(at 0 2 180)
			(size 2.95 1.02)
			(layers "F.Cu" "F.Mask" "F.Paste")
			(net "TXD_OUT")
		)
		(pad "4" smd rect
			(at 4.55 2 180)
			(size 2.95 1.02)
			(layers "F.Cu" "F.Mask" "F.Paste")
			(net "RST")
		)
		(pad "5" smd rect
			(at 0 4 180)
			(size 2.95 1.02)
			(layers "F.Cu" "F.Mask" "F.Paste")
			(net "RXD_IN")
		)
		(pad "6" smd rect
			(at 4.55 4 180)
			(size 2.95 1.02)
			(layers "F.Cu" "F.Mask" "F.Paste")
			(net "TP1")
		)
		(pad "7" smd rect
			(at 0 6 180)
			(size 2.95 1.02)
			(layers "F.Cu" "F.Mask" "F.Paste")
			(net "TP2")
		)
		(pad "8" smd rect
			(at 4.55 6 180)
			(size 2.95 1.02)
			(layers "F.Cu" "F.Mask" "F.Paste")
			(net "GND")
		)
	)
	(footprint "MyLibrary:CONN_131-3711-301"
		(locked yes)
		(layer "F.Cu")
		(at 120.7051 101.0761 -90)
		(property "Reference" "J2"
			(at -4.68273 -2.996 0)
			(unlocked yes)
			(layer "F.SilkS")
			(effects
				(font
					(size 0.8 0.8)
					(thickness 0.15)
				)
			)
		)
		(property "Value" "SMB_131-3711-301"
			(at 12.512802 -7.959285 0)
			(unlocked yes)
			(layer "F.SilkS")
			(hide yes)
			(effects
				(font
					(size 1.524 1.524)
					(thickness 0.254)
				)
			)
		)
		(sheetname "Antenna_Supervisor")
		(sheetfile "Antenna_Supervisor.kicad_sch")
		(duplicate_pad_numbers_are_jumpers no)
		(fp_line
			(start -3.8 3.8)
			(end -3.8 -3.8)
			(stroke
				(width 0.1778)
				(type solid)
			)
			(layer "F.SilkS")
		)
		(fp_line
			(start 3.8 3.8)
			(end -3.8 3.8)
			(stroke
				(width 0.1778)
				(type solid)
			)
			(layer "F.SilkS")
		)
		(fp_line
			(start 3.8 3.8)
			(end 3.8 -3.8)
			(stroke
				(width 0.1778)
				(type solid)
			)
			(layer "F.SilkS")
		)
		(fp_line
			(start 3.8 -3.8)
			(end -3.8 -3.8)
			(stroke
				(width 0.1778)
				(type solid)
			)
			(layer "F.SilkS")
		)
		(pad "" smd custom
			(at -3.58131 3.55582)
			(size 0.000001 0.000001)
			(layers "F.Cu" "F.Mask" "F.Paste")
			(solder_paste_margin -0.2)
			(thermal_bridge_angle 90)
			(options
				(clearance outline)
				(anchor circle)
			)
			(primitives
				(gr_poly
					(pts
						(xy 0 0) (xy 0 2.3622)
						(arc
							(start 1.914553 2.3622)
							(mid 3.556 1.5367)
							(end 5.197447 2.3622)
						)
						(xy 5.19744 2.3622) (xy 7.112 2.3622) (xy 7.112 0)
					)
					(width 0)
					(fill yes)
				)
			)
		)
		(pad "" smd custom
			(at -0.86351 -0.00018)
			(size 0.000001 0.000001)
			(layers "F.Cu" "F.Mask" "F.Paste")
			(solder_paste_margin -0.2)
			(thermal_bridge_angle 90)
			(options
				(clearance outline)
				(anchor circle)
			)
			(primitives
				(gr_poly
					(pts
						(arc
							(start 0 0)
							(mid -0.610657 0.252943)
							(end -0.8636 0.8636)
						)
						(arc
							(start -0.8636 0.8636)
							(mid -0.610657 1.474257)
							(end 0 1.7272)
						)
						(arc
							(start 0 1.7272)
							(mid 0.610657 1.474257)
							(end 0.8636 0.8636)
						)
						(arc
							(start 0.8636 0.8636)
							(mid 0.610657 0.252943)
							(end 0 0)
						)
					)
					(width 0)
					(fill yes)
				)
			)
		)
		(pad "" smd custom
			(at 1.21929 3.55582)
			(size 0.000001 0.000001)
			(layers "F.Cu" "F.Mask" "F.Paste")
			(solder_paste_margin -0.2)
			(thermal_bridge_angle 90)
			(options
				(clearance outline)
				(anchor circle)
			)
			(primitives
				(gr_poly
					(pts
						(xy 0 0) (xy 0 2.3622) (xy 7.112 2.3622) (xy 7.112 0)
						(arc
							(start 5.197447 0)
							(mid 3.556 0.8255)
							(end 1.914553 0)
						)
						(xy 1.91455 0)
					)
					(width 0)
					(fill yes)
				)
			)
		)
		(pad "1" smd circle
			(at 0.00009 -0.00018 270)
			(size 1 1)
			(layers "F.Cu" "F.Mask" "F.Paste")
			(net "RF_ANT")
			(solder_mask_margin 0)
			(thermal_bridge_angle 90)
		)
		(pad "2" smd rect
			(at -2.794 0.254 270)
			(size 1 5)
			(layers "F.Cu" "F.Mask" "F.Paste")
			(net "GND")
			(solder_mask_margin 0)
		)
		(pad "3" smd rect
			(at 2.91616 0 270)
			(size 1 5)
			(layers "F.Cu" "F.Mask" "F.Paste")
			(net "GND")
			(solder_mask_margin 0)
		)
	)
	(footprint "Vault:FP-RMCF0402-IPC_C"
		(layer "F.Cu")
		(at 163.7847 117.55363 -90)
		(property "Reference" "R7"
			(at 1.52194 -0.15 0)
			(unlocked yes)
			(layer "F.SilkS")
			(effects
				(font
					(size 0.8 0.8)
					(thickness 0.15)
				)
			)
		)
		(property "Value" "10k"
			(at 2.352802 -1.434525 0)
			(unlocked yes)
			(layer "F.SilkS")
			(hide yes)
			(effects
				(font
					(size 1.524 1.524)
					(thickness 0.254)
				)
			)
		)
		(sheetname "ZED-F9T")
		(sheetfile "ZED-F9T.kicad_sch")
		(duplicate_pad_numbers_are_jumpers no)
		(fp_line
			(start 0.65607 0.675)
			(end -0.65607 0.675)
			(stroke
				(width 0.2)
				(type solid)
			)
			(layer "F.SilkS")
		)
		(fp_line
			(start 0.65607 -0.675)
			(end -0.65607 -0.675)
			(stroke
				(width 0.2)
				(type solid)
			)
			(layer "F.SilkS")
		)
		(fp_line
			(start -0.75606 0.375)
			(end -0.75606 -0.375)
			(stroke
				(width 0.2)
				(type solid)
			)
			(layer "F.CrtYd")
		)
		(fp_line
			(start 0.75607 0.375)
			(end -0.75606 0.375)
			(stroke
				(width 0.2)
				(type solid)
			)
			(layer "F.CrtYd")
		)
		(fp_line
			(start 0.75607 0.375)
			(end 0.75607 -0.375)
			(stroke
				(width 0.2)
				(type solid)
			)
			(layer "F.CrtYd")
		)
		(fp_line
			(start 0.75607 -0.375)
			(end -0.75606 -0.375)
			(stroke
				(width 0.2)
				(type solid)
			)
			(layer "F.CrtYd")
		)
		(fp_line
			(start 0 0.5)
			(end 0 -0.5)
			(stroke
				(width 0.1)
				(type solid)
			)
			(layer "F.Fab")
		)
		(fp_line
			(start -0.75606 0.375)
			(end -0.75606 -0.375)
			(stroke
				(width 0.2)
				(type solid)
			)
			(layer "F.Fab")
		)
		(fp_line
			(start 0.75607 0.375)
			(end -0.75606 0.375)
			(stroke
				(width 0.2)
				(type solid)
			)
			(layer "F.Fab")
		)
		(fp_line
			(start 0.75607 0.375)
			(end 0.75607 -0.375)
			(stroke
				(width 0.2)
				(type solid)
			)
			(layer "F.Fab")
		)
		(fp_line
			(start 0.5 0)
			(end -0.5 0)
			(stroke
				(width 0.1)
				(type solid)
			)
			(layer "F.Fab")
		)
		(fp_line
			(start 0.75607 -0.375)
			(end -0.75606 -0.375)
			(stroke
				(width 0.2)
				(type solid)
			)
			(layer "F.Fab")
		)
		(fp_text user "${REFERENCE}"
			(at -0.00001 0.10711 270)
			(unlocked yes)
			(layer "F.Fab")
			(effects
				(font
					(face "Arial")
					(size 0.63 0.63)
					(thickness 0.1)
				)
				(justify left bottom)
			)
		)
		(pad "1" smd rect
			(at -0.36553 0 270)
			(size 0.58106 0.47247)
			(layers "F.Cu" "F.Mask" "F.Paste")
			(net "GND")
			(solder_mask_margin 0)
			(solder_paste_margin 0)
		)
		(pad "2" smd rect
			(at 0.36554 0 270)
			(size 0.58106 0.47247)
			(layers "F.Cu" "F.Mask" "F.Paste")
			(net "NetDS2_K")
			(solder_mask_margin 0)
			(solder_paste_margin 0)
		)
	)
	(footprint "Vault:CAPC1005X055N"
		(layer "F.Cu")
		(at 156.4441 109.1921)
		(property "Reference" "C1"
			(at 1.92171 0.02827 0)
			(unlocked yes)
			(layer "F.SilkS")
			(effects
				(font
					(size 0.8 0.8)
					(thickness 0.15)
				)
			)
		)
		(property "Value" "Murata_GRM155R61E105KA12D"
			(at 17.643125 9.764902 0)
			(unlocked yes)
			(layer "F.SilkS")
			(hide yes)
			(effects
				(font
					(size 1.524 1.524)
					(thickness 0.254)
				)
			)
		)
		(sheetname "ZED-F9T")
		(sheetfile "ZED-F9T.kicad_sch")
		(duplicate_pad_numbers_are_jumpers no)
		(fp_line
			(start -0.95 -0.5)
			(end 0.95 -0.5)
			(stroke
				(width 0.1)
				(type solid)
			)
			(layer "F.CrtYd")
		)
		(fp_line
			(start -0.95 0.5)
			(end -0.95 -0.5)
			(stroke
				(width 0.1)
				(type solid)
			)
			(layer "F.CrtYd")
		)
		(fp_line
			(start -0.95 0.5)
			(end 0.95 0.5)
			(stroke
				(width 0.1)
				(type solid)
			)
			(layer "F.CrtYd")
		)
		(fp_line
			(start 0.95 0.5)
			(end 0.95 -0.5)
			(stroke
				(width 0.1)
				(type solid)
			)
			(layer "F.CrtYd")
		)
		(fp_line
			(start -0.5 -0.25)
			(end 0.5 -0.25)
			(stroke
				(width 0.05)
				(type solid)
			)
			(layer "F.Fab")
		)
		(fp_line
			(start -0.5 0.25)
			(end -0.5 -0.25)
			(stroke
				(width 0.05)
				(type solid)
			)
			(layer "F.Fab")
		)
		(fp_line
			(start -0.5 0.25)
			(end 0.5 0.25)
			(stroke
				(width 0.05)
				(type solid)
			)
			(layer "F.Fab")
		)
		(fp_line
			(start 0.5 0.25)
			(end 0.5 -0.25)
			(stroke
				(width 0.05)
				(type solid)
			)
			(layer "F.Fab")
		)
		(fp_text_box "${REFERENCE}"
			(start -1.09004 -0.20727)
			(end 1.09004 0.20726)
			(margins 0 0 0 0)
			(layer "F.Fab")
			(effects
				(font
					(face "Arial")
					(size 0.315 0.315)
					(thickness 0.254)
				)
				(justify top)
			)
			(border no)
			(stroke
				(width 0.1)
				(type default)
			)
			(knockout no)
		)
		(pad "1" smd rect
			(at -0.46 0)
			(size 0.6 0.62)
			(layers "F.Cu" "F.Mask" "F.Paste")
			(net "VCC")
			(solder_mask_margin 0.05)
			(solder_paste_margin 0)
		)
		(pad "2" smd rect
			(at 0.46 0)
			(size 0.6 0.62)
			(layers "F.Cu" "F.Mask" "F.Paste")
			(net "GND")
			(solder_mask_margin 0.05)
			(solder_paste_margin 0)
		)
	)
)
